# BASEBOARD_FAB2 (Tioga Pass) — schematic netlist excerpt (pin names and nets, part order shuffled) for the footprints in the layout excerpt that follows; sources: Cadence DE-HDL packaged netlist, KiCad conversion of Wiwynn_Tioga_Pass_MB.brd

EU1C1  IR354XX  IR35412 IC  pkg SM  page 210
  VOS  = PVSA_CPU1
  LGND  = GND
  VCC  = VR_PVSA_CPU1_VCIN
  VDRV  = P5V_STBY
  PGND(0)  = GND
  GL(0)  = TP_PVSA_CPU1_GL_0
  PGND(1)  = GND
  SW  = VR_PVSA_CPU1_PHASE_SW
  VIN(0)  = VR_FET_SW_P12V_STBY_PVCCIN_CPU1
  VIN(1)  = VR_FET_SW_P12V_STBY_PVCCIN_CPU1
  NC  = NC
  PHASE  = VR_PVSA_CPU1_PHASE
  BOOST  = VR_PVSA_CPU1_BOOT_R
  PWM  = VR_PVSA_CPU1_PWM
  EN  = P5V_STBY
  TOUT_FLT  = A_TSENSE_PVSA_CPU1
  OCSET  = VR_PVSA_CPU1_OCSET
  IOUT  = ISENSE_PVSA_CPU1_IMON
  REFIN  = VR_PVSA_CPU1_BIREF1
  PGND(2)  = GND
  GL(1)  = TP_PVSA_CPU1_GL_1

(kicad_pcb
	(version 20260206)
	(generator "pcbnew")
	(generator_version "10.0")
	(general
		(thickness 1.6)
		(legacy_teardrops no)
	)
	(paper "A4")
	(title_block
		(title "Wiwynn_Tioga_Pass_MB.brd")
		(comment 1 "Tioga Pass / footprints 169-169 of 4770")
	)
	(layers
		(0 "F.Cu" signal "TOP")
		(4 "In1.Cu" signal "L2GND")
		(6 "In2.Cu" signal "L3")
		(8 "In3.Cu" signal "L4GND")
		(10 "In4.Cu" signal "L5")
		(12 "In5.Cu" signal "L6GND")
		(14 "In6.Cu" signal "L7VCC")
		(16 "In7.Cu" signal "L8VCC")
		(18 "In8.Cu" signal "L9GND")
		(20 "In9.Cu" signal "L10")
		(22 "In10.Cu" signal "L11GND")
		(24 "In11.Cu" signal "L12")
		(26 "In12.Cu" signal "L13GND")
		(2 "B.Cu" signal "BOTTOM")
		(9 "F.Adhes" user "F.Adhesive")
		(11 "B.Adhes" user "B.Adhesive")
		(13 "F.Paste" user "Package Geometry/Pastemask Top")
		(15 "B.Paste" user "Package Geometry/Pastemask Bottom")
		(5 "F.SilkS" user "Ref Des/Silkscreen Top")
		(7 "B.SilkS" user "Ref Des/Silkscreen Bottom")
		(1 "F.Mask" user "Board Geometry/Soldermask Top")
		(3 "B.Mask" user "Board Geometry/Soldermask Bottom")
		(17 "Dwgs.User" user "User.Drawings")
		(19 "Cmts.User" user "User.Comments")
		(21 "Eco1.User" user "User.Eco1")
		(23 "Eco2.User" user "User.Eco2")
		(25 "Edge.Cuts" user "Board Geometry/Outline")
		(27 "Margin" user)
		(31 "F.CrtYd" user "Package Geometry/Place Bound Top")
		(29 "B.CrtYd" user "Package Geometry/Place Bound Bottom")
		(35 "F.Fab" user "Ref Des/Assembly Top")
		(33 "B.Fab" user "Ref Des/Assembly Bottom")
	)
	(footprint ""
		(layer "F.Cu")
		(at 33.925002 -97.679764 90)
		(property "Reference" "EU1C1"
			(at 3.385566 -0.143002 0)
			(unlocked yes)
			(layer "F.SilkS")
			(effects
				(font
					(size 0.7874 0.5842)
					(thickness 0.1524)
				)
			)
		)
		(property "Value" ""
			(at 0 0 90)
			(layer "F.Fab")
			(effects
				(font
					(size 1.27 1.27)
				)
			)
		)
		(duplicate_pad_numbers_are_jumpers no)
		(fp_line
			(start 2.9718 -3.5052)
			(end 2.9718 3.429)
			(stroke
				(width 0.1524)
				(type default)
			)
			(layer "F.SilkS")
		)
		(fp_line
			(start -3.0099 -3.5052)
			(end 2.9718 -3.5052)
			(stroke
				(width 0.1524)
				(type default)
			)
			(layer "F.SilkS")
		)
		(fp_line
			(start 2.9718 3.429)
			(end -3.0099 3.429)
			(stroke
				(width 0.1524)
				(type default)
			)
			(layer "F.SilkS")
		)
		(fp_line
			(start -3.0099 3.429)
			(end -3.0099 -3.5052)
			(stroke
				(width 0.1524)
				(type default)
			)
			(layer "F.SilkS")
		)
		(fp_circle
			(center -3.057398 -2.678684)
			(end -3.057398 -2.551684)
			(stroke
				(width 0.254)
				(type default)
			)
			(fill no)
			(layer "F.SilkS")
		)
		(fp_poly
			(pts
				(xy -2.9972 -3.4925) (xy -2.9972 -2.6924) (xy -2.1971 -3.4925)
			)
			(stroke
				(width 0)
				(type default)
			)
			(fill yes)
			(layer "F.SilkS")
		)
		(fp_poly
			(pts
				(xy -2.549906 -3.050032) (xy -2.549906 3.050032) (xy 2.549906 3.050032) (xy 2.549906 -3.050032)
			)
			(stroke
				(width 0)
				(type default)
			)
			(fill no)
			(layer "F.CrtYd")
		)
		(fp_line
			(start 2.549906 -3.050032)
			(end 2.549906 3.050032)
			(stroke
				(width 0.1)
				(type default)
			)
			(layer "F.Fab")
		)
		(fp_line
			(start -2.549906 -3.050032)
			(end 2.549906 -3.050032)
			(stroke
				(width 0.1)
				(type default)
			)
			(layer "F.Fab")
		)
		(fp_line
			(start 2.549906 3.050032)
			(end -2.549906 3.050032)
			(stroke
				(width 0.1)
				(type default)
			)
			(layer "F.Fab")
		)
		(fp_line
			(start -2.549906 3.050032)
			(end -2.549906 -3.050032)
			(stroke
				(width 0.1)
				(type default)
			)
			(layer "F.Fab")
		)
		(fp_circle
			(center -3.057398 -2.678684)
			(end -3.057398 -2.551684)
			(stroke
				(width 0.254)
				(type default)
			)
			(fill no)
			(layer "F.Fab")
		)
		(pad "1" smd rect
			(at -2.39522 -2.279904 90)
			(size 0.7112 0.254)
			(layers "F.Cu" "F.Mask" "F.Paste")
			(net "PVSA_CPU1")
		)
		(pad "2" smd rect
			(at -2.39522 -1.83007 90)
			(size 0.7112 0.254)
			(layers "F.Cu" "F.Mask" "F.Paste")
			(net "GND")
		)
		(pad "3" smd rect
			(at -2.39522 -1.379982 90)
			(size 0.7112 0.254)
			(layers "F.Cu" "F.Mask" "F.Paste")
			(net "VR_PVSA_CPU1_VCIN")
		)
		(pad "4" smd rect
			(at -2.39522 -0.929894 90)
			(size 0.7112 0.254)
			(layers "F.Cu" "F.Mask" "F.Paste")
			(net "P5V_STBY")
		)
		(pad "5" smd rect
			(at -2.39522 -0.48006 90)
			(size 0.7112 0.254)
			(layers "F.Cu" "F.Mask" "F.Paste")
			(net "GND")
		)
		(pad "6" smd rect
			(at -2.39522 -0.029972 90)
			(size 0.7112 0.254)
			(layers "F.Cu" "F.Mask" "F.Paste")
			(net "TP_PVSA_CPU1_GL_0")
		)
		(pad "7" smd custom
			(at 0.016764 1.145032 90)
			(size 0.53975 0.53975)
			(layers "F.Cu" "F.Mask" "F.Paste")
			(net "GND")
			(options
				(clearance outline)
				(anchor circle)
			)
			(primitives
				(gr_poly
					(pts
						(xy -2.7051 1.0795) (xy -2.7051 -0.3683) (xy -0.9271 -0.3683) (xy -0.9271 -1.0795) (xy 2.7051 -1.0795)
						(xy 2.7051 1.0795)
					)
					(width 0)
					(fill yes)
				)
			)
		)
		(pad "10" smd rect
			(at -0.008382 2.874772 90)
			(size 4.3434 0.6096)
			(layers "F.Cu" "F.Mask" "F.Paste")
			(net "VR_PVSA_CPU1_PHASE_SW")
		)
		(pad "25" smd rect
			(at 1.548384 -1.283208 90)
			(size 2.3368 2.0066)
			(layers "F.Cu" "F.Mask" "F.Paste")
			(net "VR_FET_SW_P12V_STBY_PVCCIN_CPU1")
		)
		(pad "30" smd rect
			(at 2.050034 -2.895092 90)
			(size 0.254 0.7112)
			(layers "F.Cu" "F.Mask" "F.Paste")
			(net "VR_FET_SW_P12V_STBY_PVCCIN_CPU1")
		)
		(pad "31" smd rect
			(at 1.599946 -2.895092 90)
			(size 0.254 0.7112)
			(layers "F.Cu" "F.Mask" "F.Paste")
			(net "Net_295")
		)
		(pad "32" smd rect
			(at 1.150112 -2.895092 90)
			(size 0.254 0.7112)
			(layers "F.Cu" "F.Mask" "F.Paste")
			(net "VR_PVSA_CPU1_PHASE")
		)
		(pad "33" smd rect
			(at 0.700024 -2.895092 90)
			(size 0.254 0.7112)
			(layers "F.Cu" "F.Mask" "F.Paste")
			(net "VR_PVSA_CPU1_BOOT_R")
		)
		(pad "34" smd rect
			(at 0.249936 -2.895092 90)
			(size 0.254 0.7112)
			(layers "F.Cu" "F.Mask" "F.Paste")
			(net "VR_PVSA_CPU1_PWM")
		)
		(pad "35" smd rect
			(at -0.199898 -2.895092 90)
			(size 0.254 0.7112)
			(layers "F.Cu" "F.Mask" "F.Paste")
			(net "P5V_STBY")
		)
		(pad "36" smd rect
			(at -0.649986 -2.895092 90)
			(size 0.254 0.7112)
			(layers "F.Cu" "F.Mask" "F.Paste")
			(net "A_TSENSE_PVSA_CPU1")
		)
		(pad "37" smd rect
			(at -1.100074 -2.895092 90)
			(size 0.254 0.7112)
			(layers "F.Cu" "F.Mask" "F.Paste")
			(net "VR_PVSA_CPU1_OCSET")
		)
		(pad "38" smd rect
			(at -1.549908 -2.895092 90)
			(size 0.254 0.7112)
			(layers "F.Cu" "F.Mask" "F.Paste")
			(net "ISENSE_PVSA_CPU1_IMON")
		)
		(pad "39" smd rect
			(at -1.999996 -2.895092 90)
			(size 0.254 0.7112)
			(layers "F.Cu" "F.Mask" "F.Paste")
			(net "VR_PVSA_CPU1_BIREF1")
		)
		(pad "40" smd rect
			(at -0.871728 -1.283208 90)
			(size 1.8034 2.0066)
			(layers "F.Cu" "F.Mask" "F.Paste")
			(net "GND")
		)
		(pad "41" smd rect
			(at -1.533906 0.247904 90)
			(size 0.508 0.3556)
			(layers "F.Cu" "F.Mask" "F.Paste")
			(net "TP_PVSA_CPU1_GL_1")
		)
	)
)
